# TIMECARD (Time Appliance Project (Time Card)) — schematic netlist excerpt (pin names and nets, part order shuffled) for the footprints in the layout excerpt that follows; sources: Cadence DE-HDL packaged netlist, KiCad conversion of R4006-B0001-02_R01.brd

C159  CAPACITOR  4.7UF 6.3V 20%  pkg SMC_0402R_H026  page 14 : \1\ = XP3R3V_FPGA ; \2\ = SG
C42  CAPACITOR  2200PF 50V 10%  pkg SMC_0402R_H022  page 32 : \1\ = UNNAMED_516_CAPACITOR_I13_1 ; \2\ = XP5R0V_AGND

(kicad_pcb
	(version 20260206)
	(generator "pcbnew")
	(generator_version "10.0")
	(general
		(thickness 1.6)
		(legacy_teardrops no)
	)
	(paper "A4")
	(title_block
		(title "timecard-production-celestica-r4006 — R4006-B0001-02_R01.brd")
		(comment 1 "Time Appliance Project (Time Card) / footprints 966-967 of 1113")
	)
	(layers
		(0 "F.Cu" signal "TOP")
		(4 "In1.Cu" signal "L02_GND1")
		(6 "In2.Cu" signal "L03_SIG1")
		(8 "In3.Cu" signal "L04_GND2")
		(10 "In4.Cu" signal "L05_VCC1")
		(12 "In5.Cu" signal "L06_VCC2")
		(14 "In6.Cu" signal "L07_GND3")
		(16 "In7.Cu" signal "L08_SIG2")
		(18 "In8.Cu" signal "L09_GND4")
		(2 "B.Cu" signal "BOTTOM")
		(9 "F.Adhes" user "F.Adhesive")
		(11 "B.Adhes" user "B.Adhesive")
		(13 "F.Paste" user "Package Geometry/Pastemask Top")
		(15 "B.Paste" user "Package Geometry/Pastemask Bottom")
		(5 "F.SilkS" user "Ref Des/Silkscreen Top")
		(7 "B.SilkS" user "Ref Des/Silkscreen Bottom")
		(1 "F.Mask" user "Board Geometry/Soldermask Top")
		(3 "B.Mask" user "Board Geometry/Soldermask Bottom")
		(17 "Dwgs.User" user "User.Drawings")
		(19 "Cmts.User" user "User.Comments")
		(21 "Eco1.User" user "User.Eco1")
		(23 "Eco2.User" user "User.Eco2")
		(25 "Edge.Cuts" user "Board Geometry/Outline")
		(27 "Margin" user)
		(31 "F.CrtYd" user "Package Geometry/Place Bound Top")
		(29 "B.CrtYd" user "Package Geometry/Place Bound Bottom")
		(35 "F.Fab" user "Ref Des/Assembly Top")
		(33 "B.Fab" user "Ref Des/Assembly Bottom")
	)
	(footprint ""
		(layer "B.Cu")
		(at 102.743 -56.261)
		(property "Reference" "C159"
			(at 2.667 -0.01905 0)
			(unlocked yes)
			(layer "B.SilkS")
			(effects
				(font
					(size 0.635 0.4064)
					(thickness 0.1524)
				)
				(justify mirror)
			)
		)
		(property "Value" "VAL*"
			(at -0.02032 2.13233 0)
			(unlocked yes)
			(layer "B.Fab")
			(hide yes)
			(effects
				(font
					(size 0.7874 0.5842)
					(thickness 0.1524)
				)
				(justify mirror)
			)
		)
		(property "Device Type" "CAPACITOR-G105-0F475-BM,4.7UF,A"
			(at -0.008382 1.210564 0)
			(unlocked yes)
			(layer "B.Fab")
			(hide yes)
			(effects
				(font
					(size 0.7874 0.5842)
					(thickness 0.1524)
				)
				(justify mirror)
			)
		)
		(property "User Part Number" "PARTNUM*"
			(at -0.02032 4.024884 0)
			(unlocked yes)
			(layer "Cmts.User")
			(hide yes)
			(effects
				(font
					(size 0.7874 0.5842)
					(thickness 0.1524)
				)
				(justify mirror)
			)
		)
		(property "Tolerance" "TOL*"
			(at -0.044704 3.05435 0)
			(unlocked yes)
			(layer "Cmts.User")
			(hide yes)
			(effects
				(font
					(size 0.7874 0.5842)
					(thickness 0.1524)
				)
				(justify mirror)
			)
		)
		(duplicate_pad_numbers_are_jumpers no)
		(fp_line
			(start -1.143 -0.5588)
			(end 1.143 -0.5588)
			(stroke
				(width 0.1)
				(type default)
			)
			(layer "B.SilkS")
		)
		(fp_line
			(start -1.143 0.5588)
			(end -1.143 -0.5588)
			(stroke
				(width 0.1)
				(type default)
			)
			(layer "B.SilkS")
		)
		(fp_line
			(start 1.143 -0.5588)
			(end 1.143 0.5588)
			(stroke
				(width 0.1)
				(type default)
			)
			(layer "B.SilkS")
		)
		(fp_line
			(start 1.143 0.5588)
			(end -1.143 0.5588)
			(stroke
				(width 0.1)
				(type default)
			)
			(layer "B.SilkS")
		)
		(fp_rect
			(start -1.143 0.5588)
			(end 1.143 -0.5588)
			(stroke
				(width 0)
				(type default)
			)
			(fill no)
			(layer "B.CrtYd")
		)
		(fp_line
			(start -0.508 -0.3048)
			(end 0.508 -0.3048)
			(stroke
				(width 0.1)
				(type default)
			)
			(layer "B.Fab")
		)
		(fp_line
			(start -0.508 0.3048)
			(end -0.508 -0.3048)
			(stroke
				(width 0.1)
				(type default)
			)
			(layer "B.Fab")
		)
		(fp_line
			(start 0.508 -0.3048)
			(end 0.508 0.3048)
			(stroke
				(width 0.1)
				(type default)
			)
			(layer "B.Fab")
		)
		(fp_line
			(start 0.508 0.3048)
			(end -0.508 0.3048)
			(stroke
				(width 0.1)
				(type default)
			)
			(layer "B.Fab")
		)
		(pad "1" smd rect
			(at 0.5334 0 180)
			(size 0.7112 0.6096)
			(layers "B.Cu" "B.Mask" "B.Paste")
			(net "XP3R3V_FPGA")
		)
		(pad "2" smd rect
			(at -0.5334 0 180)
			(size 0.7112 0.6096)
			(layers "B.Cu" "B.Mask" "B.Paste")
			(net "SG")
		)
		(zone
			(layer "B.Cu")
			(hatch none 0.5)
			(connect_pads
				(clearance 0)
			)
			(min_thickness 0.25)
			(keepout
				(tracks allowed)
				(vias not_allowed)
				(pads allowed)
				(copperpour not_allowed)
				(footprints allowed)
			)
			(placement
				(enabled no)
				(sheetname "")
			)
			(fill
				(thermal_gap 0.5)
				(thermal_bridge_width 0.5)
				(island_removal_mode 0)
			)
			(polygon
				(pts
					(xy 102.6668 -55.9562) (xy 102.8192 -55.9562) (xy 102.8192 -56.5658) (xy 102.6668 -56.5658)
				)
			)
		)
	)
	(footprint ""
		(layer "B.Cu")
		(at 36.9824 -102.5144 180)
		(property "Reference" "C42"
			(at 4.0386 -0.64897 0)
			(unlocked yes)
			(layer "B.SilkS")
			(effects
				(font
					(size 0.7874 0.5842)
					(thickness 0.1524)
				)
				(justify mirror)
			)
		)
		(property "Value" "VAL*"
			(at -0.0762 2.067306 180)
			(unlocked yes)
			(layer "B.Fab")
			(hide yes)
			(effects
				(font
					(size 0.7874 0.5842)
					(thickness 0.1524)
				)
				(justify mirror)
			)
		)
		(property "Device Type" "CAPACITOR-G105-0B222-FK,2200PFA"
			(at -0.0508 1.127506 180)
			(unlocked yes)
			(layer "B.Fab")
			(hide yes)
			(effects
				(font
					(size 0.7874 0.5842)
					(thickness 0.1524)
				)
				(justify mirror)
			)
		)
		(property "User Part Number" "PARTNUM*"
			(at -0.1016 4.023106 180)
			(unlocked yes)
			(layer "Cmts.User")
			(hide yes)
			(effects
				(font
					(size 0.7874 0.5842)
					(thickness 0.1524)
				)
				(justify mirror)
			)
		)
		(property "Tolerance" "TOL*"
			(at -0.0762 3.032506 180)
			(unlocked yes)
			(layer "Cmts.User")
			(hide yes)
			(effects
				(font
					(size 0.7874 0.5842)
					(thickness 0.1524)
				)
				(justify mirror)
			)
		)
		(duplicate_pad_numbers_are_jumpers no)
		(fp_line
			(start 1.143 0.5588)
			(end -1.143 0.5588)
			(stroke
				(width 0.1)
				(type default)
			)
			(layer "B.SilkS")
		)
		(fp_line
			(start 1.143 -0.5588)
			(end 1.143 0.5588)
			(stroke
				(width 0.1)
				(type default)
			)
			(layer "B.SilkS")
		)
		(fp_line
			(start -1.143 0.5588)
			(end -1.143 -0.5588)
			(stroke
				(width 0.1)
				(type default)
			)
			(layer "B.SilkS")
		)
		(fp_line
			(start -1.143 -0.5588)
			(end 1.143 -0.5588)
			(stroke
				(width 0.1)
				(type default)
			)
			(layer "B.SilkS")
		)
		(fp_rect
			(start -1.143 0.5588)
			(end 1.143 -0.5588)
			(stroke
				(width 0)
				(type default)
			)
			(fill no)
			(layer "B.CrtYd")
		)
		(fp_line
			(start 0.508 0.3048)
			(end -0.508 0.3048)
			(stroke
				(width 0.1)
				(type default)
			)
			(layer "B.Fab")
		)
		(fp_line
			(start 0.508 -0.3048)
			(end 0.508 0.3048)
			(stroke
				(width 0.1)
				(type default)
			)
			(layer "B.Fab")
		)
		(fp_line
			(start -0.508 0.3048)
			(end -0.508 -0.3048)
			(stroke
				(width 0.1)
				(type default)
			)
			(layer "B.Fab")
		)
		(fp_line
			(start -0.508 -0.3048)
			(end 0.508 -0.3048)
			(stroke
				(width 0.1)
				(type default)
			)
			(layer "B.Fab")
		)
		(pad "1" smd rect
			(at 0.5334 0)
			(size 0.7112 0.6096)
			(layers "B.Cu" "B.Mask" "B.Paste")
			(net "UNNAMED_516_CAPACITOR_I13_1")
		)
		(pad "2" smd rect
			(at -0.5334 0)
			(size 0.7112 0.6096)
			(layers "B.Cu" "B.Mask" "B.Paste")
			(net "XP5R0V_AGND")
		)
		(zone
			(layer "B.Cu")
			(hatch none 0.5)
			(connect_pads
				(clearance 0)
			)
			(min_thickness 0.25)
			(keepout
				(tracks allowed)
				(vias not_allowed)
				(pads allowed)
				(copperpour not_allowed)
				(footprints allowed)
			)
			(placement
				(enabled no)
				(sheetname "")
			)
			(fill
				(thermal_gap 0.5)
				(thermal_bridge_width 0.5)
				(island_removal_mode 0)
			)
			(polygon
				(pts
					(xy 37.0586 -102.8192) (xy 36.9062 -102.8192) (xy 36.9062 -102.2096) (xy 37.0586 -102.2096)
				)
			)
		)
	)
)
